(kicad_pcb
	(version 20260206)
	(generator "pcbnew")
	(generator_version "10.0")
	(general
		(thickness 1.6)
		(legacy_teardrops no)
	)
	(paper "A4")
	(title_block
		(title "Wiwynn_Tioga_Pass_MB.brd")
		(comment 1 "Tioga Pass / footprints 2580-2586 of 4770")
	)
	(layers
		(0 "F.Cu" signal "TOP")
		(4 "In1.Cu" signal "L2GND")
		(6 "In2.Cu" signal "L3")
		(8 "In3.Cu" signal "L4GND")
		(10 "In4.Cu" signal "L5")
		(12 "In5.Cu" signal "L6GND")
		(14 "In6.Cu" signal "L7VCC")
		(16 "In7.Cu" signal "L8VCC")
		(18 "In8.Cu" signal "L9GND")
		(20 "In9.Cu" signal "L10")
		(22 "In10.Cu" signal "L11GND")
		(24 "In11.Cu" signal "L12")
		(26 "In12.Cu" signal "L13GND")
		(2 "B.Cu" signal "BOTTOM")
		(9 "F.Adhes" user "F.Adhesive")
		(11 "B.Adhes" user "B.Adhesive")
		(13 "F.Paste" user "Package Geometry/Pastemask Top")
		(15 "B.Paste" user "Package Geometry/Pastemask Bottom")
		(5 "F.SilkS" user "Ref Des/Silkscreen Top")
		(7 "B.SilkS" user "Ref Des/Silkscreen Bottom")
		(1 "F.Mask" user "Board Geometry/Soldermask Top")
		(3 "B.Mask" user "Board Geometry/Soldermask Bottom")
		(17 "Dwgs.User" user "User.Drawings")
		(19 "Cmts.User" user "User.Comments")
		(21 "Eco1.User" user "User.Eco1")
		(23 "Eco2.User" user "User.Eco2")
		(25 "Edge.Cuts" user "Board Geometry/Outline")
		(27 "Margin" user)
		(31 "F.CrtYd" user "Package Geometry/Place Bound Top")
		(29 "B.CrtYd" user "Package Geometry/Place Bound Bottom")
		(35 "F.Fab" user "Ref Des/Assembly Top")
		(33 "B.Fab" user "Ref Des/Assembly Bottom")
	)
	(footprint ""
		(layer "B.Cu")
		(at 102.946454 -68.17614 180)
		(property "Reference" "C8P34"
			(at 0 0 0)
			(layer "B.SilkS")
			(hide yes)
			(effects
				(font
					(size 1.27 1.27)
				)
				(justify mirror)
			)
		)
		(property "Value" ""
			(at 0 0 0)
			(layer "B.Fab")
			(effects
				(font
					(size 1.27 1.27)
				)
				(justify mirror)
			)
		)
		(duplicate_pad_numbers_are_jumpers no)
		(fp_poly
			(pts
				(xy 0.7239 -0.2159) (xy -0.7239 -0.2159) (xy -0.7239 1.9939) (xy 0.7239 1.9939)
			)
			(stroke
				(width 0)
				(type default)
			)
			(fill no)
			(layer "B.CrtYd")
		)
		(fp_line
			(start 0.7239 1.9939)
			(end -0.7239 1.9939)
			(stroke
				(width 0.1)
				(type default)
			)
			(layer "B.Fab")
		)
		(fp_line
			(start 0.7239 -0.2159)
			(end 0.7239 1.9939)
			(stroke
				(width 0.1)
				(type default)
			)
			(layer "B.Fab")
		)
		(fp_line
			(start -0.7239 1.9939)
			(end -0.7239 -0.2159)
			(stroke
				(width 0.1)
				(type default)
			)
			(layer "B.Fab")
		)
		(fp_line
			(start -0.7239 -0.2159)
			(end 0.7239 -0.2159)
			(stroke
				(width 0.1)
				(type default)
			)
			(layer "B.Fab")
		)
		(pad "1" smd rect
			(at 0 0)
			(size 1.27 1.016)
			(layers "B.Cu" "B.Mask" "B.Paste")
			(net "PVDDQ_GHJ")
		)
		(pad "2" smd rect
			(at 0 1.778)
			(size 1.27 1.016)
			(layers "B.Cu" "B.Mask" "B.Paste")
			(net "GND")
		)
		(zone
			(layer "B.Cu")
			(hatch none 0.5)
			(connect_pads
				(clearance 0)
			)
			(min_thickness 0.25)
			(keepout
				(tracks not_allowed)
				(vias allowed)
				(pads allowed)
				(copperpour not_allowed)
				(footprints allowed)
			)
			(placement
				(enabled no)
				(sheetname "")
			)
			(fill
				(thermal_gap 0.5)
				(thermal_bridge_width 0.5)
				(island_removal_mode 0)
			)
			(polygon
				(pts
					(xy 102.311454 -68.68414) (xy 103.581454 -68.68414) (xy 103.581454 -69.44614) (xy 102.311454 -69.44614)
				)
			)
		)
	)
	(footprint ""
		(layer "B.Cu")
		(at 373.945404 -75.495404)
		(property "Reference" "C3R3"
			(at 0 0 0)
			(layer "B.SilkS")
			(hide yes)
			(effects
				(font
					(size 1.27 1.27)
				)
				(justify mirror)
			)
		)
		(property "Value" ""
			(at 0 0 0)
			(layer "B.Fab")
			(effects
				(font
					(size 1.27 1.27)
				)
				(justify mirror)
			)
		)
		(duplicate_pad_numbers_are_jumpers no)
		(fp_rect
			(start 0.2794 0.9144)
			(end -0.2794 -0.1143)
			(stroke
				(width 0)
				(type default)
			)
			(fill no)
			(layer "B.CrtYd")
		)
		(fp_line
			(start -0.2794 -0.1143)
			(end -0.2794 0.9144)
			(stroke
				(width 0.1)
				(type default)
			)
			(layer "B.Fab")
		)
		(fp_line
			(start -0.2794 0.9144)
			(end 0.2794 0.9144)
			(stroke
				(width 0.1)
				(type default)
			)
			(layer "B.Fab")
		)
		(fp_line
			(start 0.2794 -0.1143)
			(end -0.2794 -0.1143)
			(stroke
				(width 0.1)
				(type default)
			)
			(layer "B.Fab")
		)
		(fp_line
			(start 0.2794 0.9144)
			(end 0.2794 -0.1143)
			(stroke
				(width 0.1)
				(type default)
			)
			(layer "B.Fab")
		)
		(pad "1" smd custom
			(at 0 0 270)
			(size 0.10414 0.10414)
			(layers "B.Cu" "B.Mask" "B.Paste")
			(net "P3V3_STBY")
			(options
				(clearance outline)
				(anchor circle)
			)
			(primitives
				(gr_poly
					(pts
						(xy -0.20828 -0.08636) (xy -0.20828 0.08636) (xy -0.08636 0.20828) (xy 0.086614 0.20828) (xy 0.20828 0.086614)
						(xy 0.20828 -0.08636) (xy 0.08636 -0.20828) (xy -0.08636 -0.20828)
					)
					(width 0)
					(fill yes)
				)
			)
		)
		(pad "2" smd custom
			(at 0 0.8001 270)
			(size 0.10414 0.10414)
			(layers "B.Cu" "B.Mask" "B.Paste")
			(net "GND")
			(options
				(clearance outline)
				(anchor circle)
			)
			(primitives
				(gr_poly
					(pts
						(xy -0.20828 -0.08636) (xy -0.20828 0.08636) (xy -0.08636 0.20828) (xy 0.086614 0.20828) (xy 0.20828 0.086614)
						(xy 0.20828 -0.08636) (xy 0.08636 -0.20828) (xy -0.08636 -0.20828)
					)
					(width 0)
					(fill yes)
				)
			)
		)
		(zone
			(layer "B.Cu")
			(hatch none 0.5)
			(connect_pads
				(clearance 0)
			)
			(min_thickness 0.25)
			(keepout
				(tracks allowed)
				(vias not_allowed)
				(pads allowed)
				(copperpour not_allowed)
				(footprints allowed)
			)
			(placement
				(enabled no)
				(sheetname "")
			)
			(fill
				(thermal_gap 0.5)
				(thermal_bridge_width 0.5)
				(island_removal_mode 0)
			)
			(polygon
				(pts
					(xy 374.033034 -75.285854) (xy 374.033034 -74.904854) (xy 373.857774 -74.904854) (xy 373.85752 -75.285854)
				)
			)
		)
		(zone
			(layer "B.Cu")
			(hatch none 0.5)
			(connect_pads
				(clearance 0)
			)
			(min_thickness 0.25)
			(keepout
				(tracks not_allowed)
				(vias allowed)
				(pads allowed)
				(copperpour not_allowed)
				(footprints allowed)
			)
			(placement
				(enabled no)
				(sheetname "")
			)
			(fill
				(thermal_gap 0.5)
				(thermal_bridge_width 0.5)
				(island_removal_mode 0)
			)
			(polygon
				(pts
					(xy 374.033034 -75.285854) (xy 374.033034 -74.904854) (xy 373.857774 -74.904854) (xy 373.85752 -75.285854)
				)
			)
		)
	)
	(footprint ""
		(layer "B.Cu")
		(at 445.503046 -150.810722 90)
		(property "Reference" "U25W14"
			(at 0.14986 2.621788 90)
			(unlocked yes)
			(layer "B.SilkS")
			(effects
				(font
					(size 1.27 0.964946)
					(thickness 0.000001)
				)
				(justify left mirror)
			)
		)
		(property "Value" ""
			(at 0 0 90)
			(layer "B.Fab")
			(effects
				(font
					(size 1.27 1.27)
				)
				(justify mirror)
			)
		)
		(duplicate_pad_numbers_are_jumpers no)
		(fp_circle
			(center 0.4699 -0.8382)
			(end 0.4699 -0.7112)
			(stroke
				(width 0.254)
				(type default)
			)
			(fill no)
			(layer "B.SilkS")
		)
		(fp_poly
			(pts
				(xy -0.21463 -0.450088) (xy -1.56337 -0.450088) (xy -1.56337 1.75006) (xy -0.21463 1.75006)
			)
			(stroke
				(width 0)
				(type default)
			)
			(fill no)
			(layer "B.CrtYd")
		)
		(fp_line
			(start -0.21463 -0.450088)
			(end -1.56337 -0.450088)
			(stroke
				(width 0.1)
				(type default)
			)
			(layer "B.Fab")
		)
		(fp_line
			(start -1.56337 -0.450088)
			(end -1.56337 1.75006)
			(stroke
				(width 0.1)
				(type default)
			)
			(layer "B.Fab")
		)
		(fp_line
			(start -0.21463 1.75006)
			(end -0.21463 -0.450088)
			(stroke
				(width 0.1)
				(type default)
			)
			(layer "B.Fab")
		)
		(fp_line
			(start -1.56337 1.75006)
			(end -0.21463 1.75006)
			(stroke
				(width 0.1)
				(type default)
			)
			(layer "B.Fab")
		)
		(fp_circle
			(center 0.4699 -0.8382)
			(end 0.4699 -0.7112)
			(stroke
				(width 0.254)
				(type default)
			)
			(fill no)
			(layer "B.Fab")
		)
		(pad "1" smd rect
			(at 0 0 270)
			(size 1.016 0.381)
			(layers "B.Cu" "B.Mask" "B.Paste")
			(net "Net_6509")
		)
		(pad "2" smd rect
			(at 0 0.649986 270)
			(size 1.016 0.381)
			(layers "B.Cu" "B.Mask" "B.Paste")
			(net "XDP_PRESENT_N")
		)
		(pad "3" smd rect
			(at 0 1.299972 270)
			(size 1.016 0.381)
			(layers "B.Cu" "B.Mask" "B.Paste")
			(net "GND")
		)
		(pad "4" smd rect
			(at -1.778 1.299972 270)
			(size 1.016 0.381)
			(layers "B.Cu" "B.Mask" "B.Paste")
			(net "CPU_XDP_PRESENT_N")
		)
		(pad "5" smd rect
			(at -1.778 0 270)
			(size 1.016 0.381)
			(layers "B.Cu" "B.Mask" "B.Paste")
			(net "P3V3_STBY")
		)
	)
	(footprint ""
		(layer "B.Cu")
		(at 174.5234 -146.939 -90)
		(property "Reference" "R6L8"
			(at 0 0 90)
			(layer "B.SilkS")
			(hide yes)
			(effects
				(font
					(size 1.27 1.27)
				)
				(justify mirror)
			)
		)
		(property "Value" ""
			(at 0 0 90)
			(layer "B.Fab")
			(effects
				(font
					(size 1.27 1.27)
				)
				(justify mirror)
			)
		)
		(duplicate_pad_numbers_are_jumpers no)
		(fp_rect
			(start -0.2794 -0.1016)
			(end 0.2794 0.9906)
			(stroke
				(width 0)
				(type default)
			)
			(fill no)
			(layer "B.CrtYd")
		)
		(fp_line
			(start -0.2794 0.9906)
			(end -0.2794 -0.1016)
			(stroke
				(width 0.1)
				(type default)
			)
			(layer "B.Fab")
		)
		(fp_line
			(start 0.2794 0.9906)
			(end -0.2794 0.9906)
			(stroke
				(width 0.1)
				(type default)
			)
			(layer "B.Fab")
		)
		(fp_line
			(start -0.2794 -0.1016)
			(end 0.2794 -0.1016)
			(stroke
				(width 0.1)
				(type default)
			)
			(layer "B.Fab")
		)
		(fp_line
			(start 0.2794 -0.1016)
			(end 0.2794 0.9906)
			(stroke
				(width 0.1)
				(type default)
			)
			(layer "B.Fab")
		)
		(pad "1" smd rect
			(at 0 0 90)
			(size 0.508 0.508)
			(layers "B.Cu" "B.Mask" "B.Paste")
			(net "P3V3")
		)
		(pad "2" smd rect
			(at 0 0.889 90)
			(size 0.508 0.508)
			(layers "B.Cu" "B.Mask" "B.Paste")
			(net "VR_PVTT_KLM_BIAS")
		)
		(zone
			(layer "B.Cu")
			(hatch none 0.5)
			(connect_pads
				(clearance 0)
			)
			(min_thickness 0.25)
			(keepout
				(tracks allowed)
				(vias not_allowed)
				(pads allowed)
				(copperpour not_allowed)
				(footprints allowed)
			)
			(placement
				(enabled no)
				(sheetname "")
			)
			(fill
				(thermal_gap 0.5)
				(thermal_bridge_width 0.5)
				(island_removal_mode 0)
			)
			(polygon
				(pts
					(xy 174.2694 -147.193) (xy 173.8884 -147.193) (xy 173.8884 -146.685) (xy 174.2694 -146.685)
				)
			)
		)
		(zone
			(layer "B.Cu")
			(hatch none 0.5)
			(connect_pads
				(clearance 0)
			)
			(min_thickness 0.25)
			(keepout
				(tracks not_allowed)
				(vias allowed)
				(pads allowed)
				(copperpour not_allowed)
				(footprints allowed)
			)
			(placement
				(enabled no)
				(sheetname "")
			)
			(fill
				(thermal_gap 0.5)
				(thermal_bridge_width 0.5)
				(island_removal_mode 0)
			)
			(polygon
				(pts
					(xy 174.2694 -147.193) (xy 173.8884 -147.193) (xy 173.8884 -146.685) (xy 174.2694 -146.685)
				)
			)
		)
	)
	(footprint ""
		(layer "B.Cu")
		(at 500.38 -151.0538 180)
		(property "Reference" "R6W37"
			(at 0.8382 -0.67818 180)
			(unlocked yes)
			(layer "B.SilkS")
			(effects
				(font
					(size 0.4064 0.254)
					(thickness 0.1524)
				)
				(justify left mirror)
			)
		)
		(property "Value" ""
			(at 0 0 0)
			(layer "B.Fab")
			(effects
				(font
					(size 1.27 1.27)
				)
				(justify mirror)
			)
		)
		(duplicate_pad_numbers_are_jumpers no)
		(fp_poly
			(pts
				(xy 0.2794 -0.1016) (xy -0.2794 -0.1016) (xy -0.2794 0.9906) (xy 0.2794 0.9906)
			)
			(stroke
				(width 0)
				(type default)
			)
			(fill no)
			(layer "B.CrtYd")
		)
		(fp_line
			(start 0.2794 0.9906)
			(end -0.2794 0.9906)
			(stroke
				(width 0.1)
				(type default)
			)
			(layer "B.Fab")
		)
		(fp_line
			(start 0.2794 -0.1016)
			(end 0.2794 0.9906)
			(stroke
				(width 0.1)
				(type default)
			)
			(layer "B.Fab")
		)
		(fp_line
			(start -0.2794 0.9906)
			(end -0.2794 -0.1016)
			(stroke
				(width 0.1)
				(type default)
			)
			(layer "B.Fab")
		)
		(fp_line
			(start -0.2794 -0.1016)
			(end 0.2794 -0.1016)
			(stroke
				(width 0.1)
				(type default)
			)
			(layer "B.Fab")
		)
		(pad "1" smd rect
			(at 0 0)
			(size 0.508 0.508)
			(layers "B.Cu" "B.Mask" "B.Paste")
			(net "SPA_MID_DBG2_TX_R")
		)
		(pad "2" smd rect
			(at 0 0.889)
			(size 0.508 0.508)
			(layers "B.Cu" "B.Mask" "B.Paste")
			(net "SPA_MID_DBG2_TX")
		)
		(zone
			(layer "B.Cu")
			(hatch none 0.5)
			(connect_pads
				(clearance 0)
			)
			(min_thickness 0.25)
			(keepout
				(tracks not_allowed)
				(vias allowed)
				(pads allowed)
				(copperpour not_allowed)
				(footprints allowed)
			)
			(placement
				(enabled no)
				(sheetname "")
			)
			(fill
				(thermal_gap 0.5)
				(thermal_bridge_width 0.5)
				(island_removal_mode 0)
			)
			(polygon
				(pts
					(xy 500.126 -151.6888) (xy 500.634 -151.6888) (xy 500.634 -151.3078) (xy 500.126 -151.3078)
				)
			)
		)
		(zone
			(layer "B.Cu")
			(hatch none 0.5)
			(connect_pads
				(clearance 0)
			)
			(min_thickness 0.25)
			(keepout
				(tracks allowed)
				(vias not_allowed)
				(pads allowed)
				(copperpour not_allowed)
				(footprints allowed)
			)
			(placement
				(enabled no)
				(sheetname "")
			)
			(fill
				(thermal_gap 0.5)
				(thermal_bridge_width 0.5)
				(island_removal_mode 0)
			)
			(polygon
				(pts
					(xy 500.126 -151.3078) (xy 500.634 -151.3078) (xy 500.634 -151.6888) (xy 500.126 -151.6888)
				)
			)
		)
	)
	(footprint ""
		(layer "B.Cu")
		(at 177.906426 -21.0439 90)
		(property "Reference" "R6T6"
			(at 0 0 90)
			(layer "B.SilkS")
			(hide yes)
			(effects
				(font
					(size 1.27 1.27)
				)
				(justify mirror)
			)
		)
		(property "Value" ""
			(at 0 0 90)
			(layer "B.Fab")
			(effects
				(font
					(size 1.27 1.27)
				)
				(justify mirror)
			)
		)
		(duplicate_pad_numbers_are_jumpers no)
		(fp_poly
			(pts
				(xy 0.2794 -0.1016) (xy -0.2794 -0.1016) (xy -0.2794 0.9906) (xy 0.2794 0.9906)
			)
			(stroke
				(width 0)
				(type default)
			)
			(fill no)
			(layer "B.CrtYd")
		)
		(fp_line
			(start 0.2794 -0.1016)
			(end 0.2794 0.9906)
			(stroke
				(width 0.1)
				(type default)
			)
			(layer "B.Fab")
		)
		(fp_line
			(start -0.2794 -0.1016)
			(end 0.2794 -0.1016)
			(stroke
				(width 0.1)
				(type default)
			)
			(layer "B.Fab")
		)
		(fp_line
			(start 0.2794 0.9906)
			(end -0.2794 0.9906)
			(stroke
				(width 0.1)
				(type default)
			)
			(layer "B.Fab")
		)
		(fp_line
			(start -0.2794 0.9906)
			(end -0.2794 -0.1016)
			(stroke
				(width 0.1)
				(type default)
			)
			(layer "B.Fab")
		)
		(pad "1" smd rect
			(at 0 0 270)
			(size 0.508 0.508)
			(layers "B.Cu" "B.Mask" "B.Paste")
			(net "PVCCIO_CPU1")
		)
		(pad "2" smd rect
			(at 0 0.889 270)
			(size 0.508 0.508)
			(layers "B.Cu" "B.Mask" "B.Paste")
			(net "XDP_CPU1_TDI")
		)
		(zone
			(layer "B.Cu")
			(hatch none 0.5)
			(connect_pads
				(clearance 0)
			)
			(min_thickness 0.25)
			(keepout
				(tracks allowed)
				(vias not_allowed)
				(pads allowed)
				(copperpour not_allowed)
				(footprints allowed)
			)
			(placement
				(enabled no)
				(sheetname "")
			)
			(fill
				(thermal_gap 0.5)
				(thermal_bridge_width 0.5)
				(island_removal_mode 0)
			)
			(polygon
				(pts
					(xy 178.160426 -21.2979) (xy 178.160426 -20.7899) (xy 178.541426 -20.7899) (xy 178.541426 -21.2979)
				)
			)
		)
		(zone
			(layer "B.Cu")
			(hatch none 0.5)
			(connect_pads
				(clearance 0)
			)
			(min_thickness 0.25)
			(keepout
				(tracks not_allowed)
				(vias allowed)
				(pads allowed)
				(copperpour not_allowed)
				(footprints allowed)
			)
			(placement
				(enabled no)
				(sheetname "")
			)
			(fill
				(thermal_gap 0.5)
				(thermal_bridge_width 0.5)
				(island_removal_mode 0)
			)
			(polygon
				(pts
					(xy 178.541426 -21.2979) (xy 178.541426 -20.7899) (xy 178.160426 -20.7899) (xy 178.160426 -21.2979)
				)
			)
		)
	)
	(footprint ""
		(layer "B.Cu")
		(at 446.381632 -35.8775 90)
		(property "Reference" "R25W6"
			(at 0 0 90)
			(layer "B.SilkS")
			(hide yes)
			(effects
				(font
					(size 1.27 1.27)
				)
				(justify mirror)
			)
		)
		(property "Value" "*"
			(at -0.064008 -4.108196 90)
			(unlocked yes)
			(layer "B.Fab")
			(hide yes)
			(effects
				(font
					(size 1.27 1.016)
					(thickness 0.1524)
				)
				(justify mirror)
			)
		)
		(property "Device Type" "120R2F-GP_RCL_GP-120R2F-GP,64.A"
			(at -0.064008 -5.632196 90)
			(unlocked yes)
			(layer "B.Fab")
			(hide yes)
			(effects
				(font
					(size 1.27 1.016)
					(thickness 0.1524)
				)
				(justify mirror)
			)
		)
		(duplicate_pad_numbers_are_jumpers no)
		(fp_line
			(start 0.508 -0.9398)
			(end 0.508 0.9398)
			(stroke
				(width 0.1524)
				(type default)
			)
			(layer "B.SilkS")
		)
		(fp_line
			(start -0.508 -0.9398)
			(end 0.508 -0.9398)
			(stroke
				(width 0.1524)
				(type default)
			)
			(layer "B.SilkS")
		)
		(fp_rect
			(start 0.508 0.9398)
			(end -0.508 -0.9398)
			(stroke
				(width 0)
				(type default)
			)
			(fill no)
			(layer "B.CrtYd")
		)
		(fp_rect
			(start 0.508 0.9398)
			(end -0.508 -0.9398)
			(stroke
				(width 0)
				(type default)
			)
			(fill no)
			(layer "B.Fab")
		)
		(pad "1" smd custom
			(at 0 -0.4445 270)
			(size 0.1397 0.1397)
			(layers "B.Cu" "B.Mask" "B.Paste")
			(net "GND")
			(options
				(clearance outline)
				(anchor circle)
			)
			(primitives
				(gr_poly
					(pts
						(arc
							(start -0.1778 0.2794)
							(mid -0.249642 0.249642)
							(end -0.2794 0.1778)
						)
						(arc
							(start -0.2794 -0.1778)
							(mid -0.249642 -0.249642)
							(end -0.1778 -0.2794)
						)
						(arc
							(start 0.1778 -0.2794)
							(mid 0.249642 -0.249642)
							(end 0.2794 -0.1778)
						)
						(arc
							(start 0.2794 0.1778)
							(mid 0.249642 0.249642)
							(end 0.1778 0.2794)
						)
					)
					(width 0)
					(fill yes)
				)
			)
		)
		(pad "2" smd custom
			(at 0 0.4445 270)
			(size 0.1397 0.1397)
			(layers "B.Cu" "B.Mask" "B.Paste")
			(net "BMC_M_RAS_N")
			(options
				(clearance outline)
				(anchor circle)
			)
			(primitives
				(gr_poly
					(pts
						(arc
							(start -0.1778 0.2794)
							(mid -0.249642 0.249642)
							(end -0.2794 0.1778)
						)
						(arc
							(start -0.2794 -0.1778)
							(mid -0.249642 -0.249642)
							(end -0.1778 -0.2794)
						)
						(arc
							(start 0.1778 -0.2794)
							(mid 0.249642 -0.249642)
							(end 0.2794 -0.1778)
						)
						(arc
							(start 0.2794 0.1778)
							(mid 0.249642 0.249642)
							(end 0.1778 0.2794)
						)
					)
					(width 0)
					(fill yes)
				)
			)
		)
	)
)
